# T6G (Grand Teton) — schematic netlist excerpt (pin names and nets, part order shuffled) for the footprints in the layout excerpt that follows; sources: Cadence DE-HDL packaged netlist, KiCad conversion of 04192023_DAF0TMB3IC0_F0TG_MB_C_brd_V02_OCP.brd

C6542  Q_CAP_DIFFBUS  DIFF BUS_0.22UF 6.3V 20% X6S  pkg C0201  page 286 : \1\ = P5E_CPU0_P1_TX_BUF_C_DN<4> ; \2\ = P5E_CPU0_P1_TX_BUF_DN<4>
C2122  Q_CAP  22UF 4V 20% X6S  pkg C0402  page 74 : A = PVDDIO_P1 ; B = GND
PC134_6  Q_CAP  22UF 4V 20% X6S  pkg C0805  page 213 : A = PVDDCR_CPU0_P1 ; B = GND

(kicad_pcb
	(version 20260206)
	(generator "pcbnew")
	(generator_version "10.0")
	(general
		(thickness 1.6)
		(legacy_teardrops no)
	)
	(paper "A4")
	(title_block
		(title "04192023_DAF0TMB3IC0_F0TG_MB_C_brd_V02_OCP.brd")
		(comment 1 "Grand Teton / footprints 7591-7593 of 8354")
	)
	(layers
		(0 "F.Cu" signal "TOP")
		(4 "In1.Cu" signal "GND")
		(6 "In2.Cu" signal "IN1")
		(8 "In3.Cu" signal "GND1")
		(10 "In4.Cu" signal "IN2")
		(12 "In5.Cu" signal "GND2")
		(14 "In6.Cu" signal "IN3")
		(16 "In7.Cu" signal "GND3")
		(18 "In8.Cu" signal "VCC")
		(20 "In9.Cu" signal "VCC1")
		(22 "In10.Cu" signal "GND4")
		(24 "In11.Cu" signal "IN4")
		(26 "In12.Cu" signal "GND5")
		(28 "In13.Cu" signal "IN5")
		(30 "In14.Cu" signal "GND6")
		(32 "In15.Cu" signal "IN6")
		(34 "In16.Cu" signal "GND7")
		(2 "B.Cu" signal "BOTTOM")
		(9 "F.Adhes" user "F.Adhesive")
		(11 "B.Adhes" user "B.Adhesive")
		(13 "F.Paste" user "Package Geometry/Pastemask Top")
		(15 "B.Paste" user "Package Geometry/Pastemask Bottom")
		(5 "F.SilkS" user "Ref Des/Silkscreen Top")
		(7 "B.SilkS" user "Ref Des/Silkscreen Bottom")
		(1 "F.Mask" user "Board Geometry/Soldermask Top")
		(3 "B.Mask" user "Board Geometry/Soldermask Bottom")
		(17 "Dwgs.User" user "User.Drawings")
		(19 "Cmts.User" user "User.Comments")
		(21 "Eco1.User" user "User.Eco1")
		(23 "Eco2.User" user "User.Eco2")
		(25 "Edge.Cuts" user "Board Geometry/Outline")
		(27 "Margin" user)
		(31 "F.CrtYd" user "Package Geometry/Place Bound Top")
		(29 "B.CrtYd" user "Package Geometry/Place Bound Bottom")
		(35 "F.Fab" user "Ref Des/Assembly Top")
		(33 "B.Fab" user "Ref Des/Assembly Bottom")
	)
	(footprint ""
		(layer "B.Cu")
		(at 61.140594 -177.380392 90)
		(property "Reference" "PC134_6"
			(at 0 0 90)
			(layer "B.SilkS")
			(hide yes)
			(effects
				(font
					(size 1.27 1.27)
				)
				(justify mirror)
			)
		)
		(property "Value" ""
			(at 0 0 90)
			(layer "B.Fab")
			(effects
				(font
					(size 1.27 1.27)
				)
				(justify mirror)
			)
		)
		(duplicate_pad_numbers_are_jumpers no)
		(fp_line
			(start 1.524 -0.762)
			(end -1.524 -0.762)
			(stroke
				(width 0.1524)
				(type default)
			)
			(layer "B.SilkS")
		)
		(fp_line
			(start -1.524 -0.762)
			(end -1.524 0.762)
			(stroke
				(width 0.1524)
				(type default)
			)
			(layer "B.SilkS")
		)
		(fp_line
			(start 1.524 0.762)
			(end 1.524 -0.762)
			(stroke
				(width 0.1524)
				(type default)
			)
			(layer "B.SilkS")
		)
		(fp_line
			(start -1.524 0.762)
			(end 1.524 0.762)
			(stroke
				(width 0.1524)
				(type default)
			)
			(layer "B.SilkS")
		)
		(fp_line
			(start 1.1049 -0.724916)
			(end 1.1049 0.724916)
			(stroke
				(width 0.1)
				(type default)
			)
			(layer "B.Fab")
		)
		(fp_line
			(start -1.1049 -0.724916)
			(end 1.1049 -0.724916)
			(stroke
				(width 0.1)
				(type default)
			)
			(layer "B.Fab")
		)
		(fp_line
			(start 1.1049 0.724916)
			(end -1.1049 0.724916)
			(stroke
				(width 0.1)
				(type default)
			)
			(layer "B.Fab")
		)
		(fp_line
			(start -1.1049 0.724916)
			(end -1.1049 -0.724916)
			(stroke
				(width 0.1)
				(type default)
			)
			(layer "B.Fab")
		)
		(pad "1" smd rect
			(at 0.889 0 90)
			(size 1.016 1.27)
			(layers "B.Cu" "B.Mask" "B.Paste")
			(net "PVDDCR_CPU0_P1")
		)
		(pad "2" smd rect
			(at -0.889 0 90)
			(size 1.016 1.27)
			(layers "B.Cu" "B.Mask" "B.Paste")
			(net "GND")
		)
	)
	(footprint ""
		(layer "B.Cu")
		(at 108.355892 -258.795266 180)
		(property "Reference" "C2122"
			(at 0 0 0)
			(layer "B.SilkS")
			(hide yes)
			(effects
				(font
					(size 1.27 1.27)
				)
				(justify mirror)
			)
		)
		(property "Value" ""
			(at 0 0 0)
			(layer "B.Fab")
			(effects
				(font
					(size 1.27 1.27)
				)
				(justify mirror)
			)
		)
		(duplicate_pad_numbers_are_jumpers no)
		(fp_line
			(start 0.7874 0.4064)
			(end 0.7874 -0.4064)
			(stroke
				(width 0.1524)
				(type default)
			)
			(layer "B.SilkS")
		)
		(fp_line
			(start 0.7874 -0.4064)
			(end -0.7874 -0.4064)
			(stroke
				(width 0.1524)
				(type default)
			)
			(layer "B.SilkS")
		)
		(fp_line
			(start -0.7874 0.4064)
			(end 0.7874 0.4064)
			(stroke
				(width 0.1524)
				(type default)
			)
			(layer "B.SilkS")
		)
		(fp_line
			(start -0.7874 -0.4064)
			(end -0.7874 0.4064)
			(stroke
				(width 0.1524)
				(type default)
			)
			(layer "B.SilkS")
		)
		(fp_line
			(start 0.67945 0.3048)
			(end 0.67945 -0.305054)
			(stroke
				(width 0.1)
				(type default)
			)
			(layer "B.Fab")
		)
		(fp_line
			(start 0.67945 -0.305054)
			(end 0.12065 -0.305054)
			(stroke
				(width 0.1)
				(type default)
			)
			(layer "B.Fab")
		)
		(fp_line
			(start 0.12065 0.3048)
			(end 0.67945 0.3048)
			(stroke
				(width 0.1)
				(type default)
			)
			(layer "B.Fab")
		)
		(fp_line
			(start 0.12065 0.2794)
			(end 0.12065 0.3048)
			(stroke
				(width 0.1)
				(type default)
			)
			(layer "B.Fab")
		)
		(fp_line
			(start 0.12065 -0.2794)
			(end -0.12065 -0.2794)
			(stroke
				(width 0.1)
				(type default)
			)
			(layer "B.Fab")
		)
		(fp_line
			(start 0.12065 -0.305054)
			(end 0.12065 -0.2794)
			(stroke
				(width 0.1)
				(type default)
			)
			(layer "B.Fab")
		)
		(fp_line
			(start -0.120396 0.3048)
			(end -0.120396 0.2794)
			(stroke
				(width 0.1)
				(type default)
			)
			(layer "B.Fab")
		)
		(fp_line
			(start -0.120396 0.2794)
			(end 0.12065 0.2794)
			(stroke
				(width 0.1)
				(type default)
			)
			(layer "B.Fab")
		)
		(fp_line
			(start -0.12065 -0.2794)
			(end -0.12065 -0.3048)
			(stroke
				(width 0.1)
				(type default)
			)
			(layer "B.Fab")
		)
		(fp_line
			(start -0.12065 -0.3048)
			(end -0.67945 -0.3048)
			(stroke
				(width 0.1)
				(type default)
			)
			(layer "B.Fab")
		)
		(fp_line
			(start -0.67945 0.3048)
			(end -0.120396 0.3048)
			(stroke
				(width 0.1)
				(type default)
			)
			(layer "B.Fab")
		)
		(fp_line
			(start -0.67945 -0.3048)
			(end -0.67945 0.3048)
			(stroke
				(width 0.1)
				(type default)
			)
			(layer "B.Fab")
		)
		(pad "1" smd circle
			(at 0.40005 0)
			(size 0 0)
			(layers "B.Cu" "B.Mask" "B.Paste")
			(net "PVDDIO_P1")
		)
		(pad "2" smd circle
			(at -0.40005 0)
			(size 0 0)
			(layers "B.Cu" "B.Mask" "B.Paste")
			(net "GND")
		)
	)
	(footprint ""
		(layer "B.Cu")
		(at 317.553086 -416.899344 90)
		(property "Reference" "C6542"
			(at 0 0 90)
			(layer "B.SilkS")
			(hide yes)
			(effects
				(font
					(size 1.27 1.27)
				)
				(justify mirror)
			)
		)
		(property "Value" ""
			(at 0 0 90)
			(layer "B.Fab")
			(effects
				(font
					(size 1.27 1.27)
				)
				(justify mirror)
			)
		)
		(duplicate_pad_numbers_are_jumpers no)
		(fp_line
			(start 0.299974 -0.150114)
			(end -0.299974 -0.150114)
			(stroke
				(width 0.1)
				(type default)
			)
			(layer "B.Fab")
		)
		(fp_line
			(start -0.299974 -0.150114)
			(end -0.299974 0.150114)
			(stroke
				(width 0.1)
				(type default)
			)
			(layer "B.Fab")
		)
		(fp_line
			(start 0.299974 0.150114)
			(end 0.299974 -0.150114)
			(stroke
				(width 0.1)
				(type default)
			)
			(layer "B.Fab")
		)
		(fp_line
			(start -0.299974 0.150114)
			(end 0.299974 0.150114)
			(stroke
				(width 0.1)
				(type default)
			)
			(layer "B.Fab")
		)
		(pad "1" smd rect
			(at 0.2667 0 270)
			(size 0.3048 0.381)
			(layers "B.Cu" "B.Mask" "B.Paste")
			(net "P5E_CPU0_P1_TX_BUF_C_DN<4>")
		)
		(pad "2" smd rect
			(at -0.2667 0 270)
			(size 0.3048 0.381)
			(layers "B.Cu" "B.Mask" "B.Paste")
			(net "P5E_CPU0_P1_TX_BUF_DN<4>")
		)
	)
)
